(kicad_pcb
	(version 20260206)
	(generator "pcbnew")
	(generator_version "10.0")
	(general
		(thickness 1.6)
		(legacy_teardrops no)
	)
	(paper "A4")
	(title_block
		(title "Bryce Canyon_F.DPB_16315-1-OCP.brd")
		(comment 1 "Bryce Canyon / footprints 1826-1831 of 2223")
	)
	(layers
		(0 "F.Cu" signal "TOP")
		(4 "In1.Cu" signal "L2GND")
		(6 "In2.Cu" signal "L3")
		(8 "In3.Cu" signal "L4GND")
		(10 "In4.Cu" signal "L5")
		(12 "In5.Cu" signal "L6VCC")
		(14 "In6.Cu" signal "L7VCC")
		(16 "In7.Cu" signal "L8")
		(18 "In8.Cu" signal "L9GND")
		(20 "In9.Cu" signal "L10")
		(22 "In10.Cu" signal "L11GND")
		(2 "B.Cu" signal "BOTTOM")
		(9 "F.Adhes" user "F.Adhesive")
		(11 "B.Adhes" user "B.Adhesive")
		(13 "F.Paste" user "Package Geometry/Pastemask Top")
		(15 "B.Paste" user "Package Geometry/Pastemask Bottom")
		(5 "F.SilkS" user "Ref Des/Silkscreen Top")
		(7 "B.SilkS" user "Ref Des/Silkscreen Bottom")
		(1 "F.Mask" user "Board Geometry/Soldermask Top")
		(3 "B.Mask" user "Board Geometry/Soldermask Bottom")
		(17 "Dwgs.User" user "User.Drawings")
		(19 "Cmts.User" user "User.Comments")
		(21 "Eco1.User" user "User.Eco1")
		(23 "Eco2.User" user "User.Eco2")
		(25 "Edge.Cuts" user "Board Geometry/Outline")
		(27 "Margin" user)
		(31 "F.CrtYd" user "Package Geometry/Place Bound Top")
		(29 "B.CrtYd" user "Package Geometry/Place Bound Bottom")
		(35 "F.Fab" user "Ref Des/Assembly Top")
		(33 "B.Fab" user "Ref Des/Assembly Bottom")
	)
	(footprint ""
		(layer "F.Cu")
		(at 458.3049 -275.252942 -90)
		(property "Reference" "Q61"
			(at 0 0 270)
			(layer "F.SilkS")
			(hide yes)
			(effects
				(font
					(size 1.27 1.27)
				)
			)
		)
		(property "Value" "2N7002KDW-GP"
			(at -2.3622 -8.2042 270)
			(unlocked yes)
			(layer "F.Fab")
			(hide yes)
			(effects
				(font
					(size 1.016 1.016)
					(thickness 0.1524)
				)
			)
		)
		(property "Device Type" "SOT-363H44"
			(at -2.3622 -10.1092 270)
			(unlocked yes)
			(layer "F.Fab")
			(hide yes)
			(effects
				(font
					(size 1.016 1.016)
					(thickness 0.1524)
				)
			)
		)
		(duplicate_pad_numbers_are_jumpers no)
		(fp_line
			(start -1.4478 1.7018)
			(end 1.4478 1.7018)
			(stroke
				(width 0.1524)
				(type default)
			)
			(layer "F.SilkS")
		)
		(fp_line
			(start 1.4478 1.7018)
			(end 1.4478 -1.7018)
			(stroke
				(width 0.1524)
				(type default)
			)
			(layer "F.SilkS")
		)
		(fp_line
			(start -1.27 1.524)
			(end -1.27 0.6604)
			(stroke
				(width 0.4826)
				(type default)
			)
			(layer "F.SilkS")
		)
		(fp_line
			(start -1.4478 -1.7018)
			(end -1.4478 1.7018)
			(stroke
				(width 0.1524)
				(type default)
			)
			(layer "F.SilkS")
		)
		(fp_line
			(start 1.4478 -1.7018)
			(end -1.4478 -1.7018)
			(stroke
				(width 0.1524)
				(type default)
			)
			(layer "F.SilkS")
		)
		(fp_poly
			(pts
				(xy -1.524 -1.778) (xy 1.524 -1.778) (xy 1.524 1.778) (xy -1.524 1.778)
			)
			(stroke
				(width 0)
				(type default)
			)
			(fill no)
			(layer "F.CrtYd")
		)
		(fp_poly
			(pts
				(xy -1.524 -1.778) (xy 1.524 -1.778) (xy 1.524 1.778) (xy -1.524 1.778)
			)
			(stroke
				(width 0)
				(type default)
			)
			(fill no)
			(layer "F.Fab")
		)
		(pad "1" smd rect
			(at -0.65024 0.9398 270)
			(size 0.4064 1.016)
			(layers "F.Cu" "F.Mask" "F.Paste")
			(net "GND")
		)
		(pad "2" smd rect
			(at 0 0.9398 270)
			(size 0.4064 1.016)
			(layers "F.Cu" "F.Mask" "F.Paste")
			(net "SW_PWR_R_HDD10")
		)
		(pad "3" smd rect
			(at 0.65024 0.9398 270)
			(size 0.4064 1.016)
			(layers "F.Cu" "F.Mask" "F.Paste")
			(net "SW_HDD_P10")
		)
		(pad "4" smd rect
			(at 0.65024 -0.9398 270)
			(size 0.4064 1.016)
			(layers "F.Cu" "F.Mask" "F.Paste")
			(net "GND")
		)
		(pad "5" smd rect
			(at 0 -0.9398 270)
			(size 0.4064 1.016)
			(layers "F.Cu" "F.Mask" "F.Paste")
			(net "SW_HDD_G10")
		)
		(pad "6" smd rect
			(at -0.65024 -0.9398 270)
			(size 0.4064 1.016)
			(layers "F.Cu" "F.Mask" "F.Paste")
			(net "SW_HDD_R10")
		)
	)
	(footprint ""
		(layer "F.Cu")
		(at 14.842998 -174.857918)
		(property "Reference" "Q74"
			(at 0 0 0)
			(layer "F.SilkS")
			(hide yes)
			(effects
				(font
					(size 1.27 1.27)
				)
			)
		)
		(property "Value" "AO4407AL-GP"
			(at -3.707384 -1.5367 0)
			(unlocked yes)
			(layer "F.Fab")
			(hide yes)
			(effects
				(font
					(size 1.016 1.016)
					(thickness 0.1524)
				)
			)
		)
		(property "Device Type" "SOIC8H69"
			(at -3.707384 -3.0607 0)
			(unlocked yes)
			(layer "F.Fab")
			(hide yes)
			(effects
				(font
					(size 1.016 1.016)
					(thickness 0.1524)
				)
			)
		)
		(duplicate_pad_numbers_are_jumpers no)
		(fp_line
			(start -2.7432 -1.4224)
			(end -2.7432 1.4224)
			(stroke
				(width 0.1524)
				(type default)
			)
			(layer "F.SilkS")
		)
		(fp_line
			(start -2.7432 1.4224)
			(end -2.6416 1.4224)
			(stroke
				(width 0.1524)
				(type default)
			)
			(layer "F.SilkS")
		)
		(fp_line
			(start -2.7432 1.4224)
			(end 2.1336 1.4224)
			(stroke
				(width 0.1524)
				(type default)
			)
			(layer "F.SilkS")
		)
		(fp_line
			(start -2.7178 -0.508)
			(end -2.1844 -0.0508)
			(stroke
				(width 0.1524)
				(type default)
			)
			(layer "F.SilkS")
		)
		(fp_line
			(start -2.6289 3.4417)
			(end -2.6289 1.4732)
			(stroke
				(width 0.381)
				(type default)
			)
			(layer "F.SilkS")
		)
		(fp_line
			(start -2.1844 -0.0508)
			(end -2.7178 0.508)
			(stroke
				(width 0.1524)
				(type default)
			)
			(layer "F.SilkS")
		)
		(fp_line
			(start 2.1336 -1.4224)
			(end -2.7432 -1.4224)
			(stroke
				(width 0.1524)
				(type default)
			)
			(layer "F.SilkS")
		)
		(fp_line
			(start 2.1336 1.4224)
			(end 2.1336 -1.4224)
			(stroke
				(width 0.1524)
				(type default)
			)
			(layer "F.SilkS")
		)
		(fp_poly
			(pts
				(xy -2.2098 -1.4224) (xy -2.2098 1.4224) (xy 2.2098 1.4224) (xy 2.2098 -1.4224)
			)
			(stroke
				(width 0)
				(type default)
			)
			(fill yes)
			(layer "F.SilkS")
		)
		(fp_rect
			(start -2.450084 2.999994)
			(end 2.450084 -2.999994)
			(stroke
				(width 0)
				(type default)
			)
			(fill no)
			(layer "F.CrtYd")
		)
		(fp_poly
			(pts
				(xy -2.8194 3.6322) (xy -2.8194 -3.6322) (xy 2.8194 -3.6322) (xy 2.8194 1.18364) (xy 2.450084 1.18364)
				(xy 2.450084 -2.999994) (xy -2.450084 -2.999994) (xy -2.450084 2.999994) (xy 2.450084 2.999994)
				(xy 2.450084 1.18618) (xy 2.8194 1.18618) (xy 2.8194 3.6322)
			)
			(stroke
				(width 0)
				(type default)
			)
			(fill no)
			(layer "F.CrtYd")
		)
		(fp_rect
			(start -2.8194 3.6322)
			(end 2.8194 -3.6322)
			(stroke
				(width 0)
				(type default)
			)
			(fill no)
			(layer "F.Fab")
		)
		(pad "1" smd rect
			(at -1.905 2.54)
			(size 0.635 1.651)
			(layers "F.Cu" "F.Mask" "F.Paste")
			(net "P12V_A")
		)
		(pad "2" smd rect
			(at -0.635 2.54)
			(size 0.635 1.651)
			(layers "F.Cu" "F.Mask" "F.Paste")
			(net "P12V_A")
		)
		(pad "3" smd rect
			(at 0.635 2.54)
			(size 0.635 1.651)
			(layers "F.Cu" "F.Mask" "F.Paste")
			(net "P12V_A")
		)
		(pad "4" smd rect
			(at 1.905 2.54)
			(size 0.635 1.651)
			(layers "F.Cu" "F.Mask" "F.Paste")
			(net "SW_HDD_N12")
		)
		(pad "5" smd rect
			(at 1.905 -2.54)
			(size 0.635 1.651)
			(layers "F.Cu" "F.Mask" "F.Paste")
			(net "P12V_HDD12")
		)
		(pad "6" smd rect
			(at 0.635 -2.54)
			(size 0.635 1.651)
			(layers "F.Cu" "F.Mask" "F.Paste")
			(net "P12V_HDD12")
		)
		(pad "7" smd rect
			(at -0.635 -2.54)
			(size 0.635 1.651)
			(layers "F.Cu" "F.Mask" "F.Paste")
			(net "P12V_HDD12")
		)
		(pad "8" smd rect
			(at -1.905 -2.54)
			(size 0.635 1.651)
			(layers "F.Cu" "F.Mask" "F.Paste")
			(net "P12V_HDD12")
		)
	)
	(footprint ""
		(layer "F.Cu")
		(at 447.834512 -43.660568 -90)
		(property "Reference" "C481"
			(at 0 0 270)
			(layer "F.SilkS")
			(hide yes)
			(effects
				(font
					(size 1.27 1.27)
				)
			)
		)
		(property "Value" "SCD01U16V1KX-GP"
			(at -2.8321 -1.7399 270)
			(unlocked yes)
			(layer "F.Fab")
			(hide yes)
			(effects
				(font
					(size 1.016 1.016)
					(thickness 0.1524)
				)
			)
		)
		(property "Device Type" "C0201H13"
			(at -2.8321 -3.2639 270)
			(unlocked yes)
			(layer "F.Fab")
			(hide yes)
			(effects
				(font
					(size 1.016 1.016)
					(thickness 0.1524)
				)
			)
		)
		(duplicate_pad_numbers_are_jumpers no)
		(fp_rect
			(start -0.2794 0.6477)
			(end 0.2794 -0.6477)
			(stroke
				(width 0)
				(type default)
			)
			(fill no)
			(layer "F.CrtYd")
		)
		(fp_rect
			(start -0.2794 0.6477)
			(end 0.2794 -0.6477)
			(stroke
				(width 0)
				(type default)
			)
			(fill no)
			(layer "F.Fab")
		)
		(pad "1" smd custom
			(at 0 -0.2794 270)
			(size 0.0762 0.0762)
			(layers "F.Cu" "F.Mask" "F.Paste")
			(net "SAS_HDD_RX_P34")
			(options
				(clearance outline)
				(anchor circle)
			)
			(primitives
				(gr_poly
					(pts
						(arc
							(start 0.1524 -0.127)
							(mid 0.137521 -0.162921)
							(end 0.1016 -0.1778)
						)
						(arc
							(start -0.1016 -0.1778)
							(mid -0.137521 -0.162921)
							(end -0.1524 -0.127)
						)
						(arc
							(start -0.1524 0.127)
							(mid -0.137521 0.162921)
							(end -0.1016 0.1778)
						)
						(arc
							(start 0.1016 0.1778)
							(mid 0.137521 0.162921)
							(end 0.1524 0.127)
						)
					)
					(width 0)
					(fill yes)
				)
			)
		)
		(pad "2" smd custom
			(at 0 0.2794 270)
			(size 0.0762 0.0762)
			(layers "F.Cu" "F.Mask" "F.Paste")
			(net "PHY_SCC_A_TO_DRV_A_34_DP")
			(options
				(clearance outline)
				(anchor circle)
			)
			(primitives
				(gr_poly
					(pts
						(arc
							(start 0.1524 -0.127)
							(mid 0.137521 -0.162921)
							(end 0.1016 -0.1778)
						)
						(arc
							(start -0.1016 -0.1778)
							(mid -0.137521 -0.162921)
							(end -0.1524 -0.127)
						)
						(arc
							(start -0.1524 0.127)
							(mid -0.137521 0.162921)
							(end -0.1016 0.1778)
						)
						(arc
							(start 0.1016 0.1778)
							(mid 0.137521 0.162921)
							(end 0.1524 0.127)
						)
					)
					(width 0)
					(fill yes)
				)
			)
		)
	)
	(footprint ""
		(layer "F.Cu")
		(at 282.3464 22.7584 -90)
		(property "Reference" "R16"
			(at 0 0 270)
			(layer "F.SilkS")
			(hide yes)
			(effects
				(font
					(size 1.27 1.27)
				)
			)
		)
		(property "Value" "0R2J-2-GP"
			(at 0.064008 -3.993896 270)
			(unlocked yes)
			(layer "F.Fab")
			(hide yes)
			(effects
				(font
					(size 1.016 1.016)
					(thickness 0.1524)
				)
			)
		)
		(property "Device Type" "R402H16"
			(at 0.064008 -5.517896 270)
			(unlocked yes)
			(layer "F.Fab")
			(hide yes)
			(effects
				(font
					(size 1.016 1.016)
					(thickness 0.1524)
				)
			)
		)
		(duplicate_pad_numbers_are_jumpers no)
		(fp_line
			(start -0.508 -0.9398)
			(end -0.508 0.9398)
			(stroke
				(width 0.1524)
				(type default)
			)
			(layer "F.SilkS")
		)
		(fp_line
			(start 0.508 -0.9398)
			(end -0.508 -0.9398)
			(stroke
				(width 0.1524)
				(type default)
			)
			(layer "F.SilkS")
		)
		(fp_rect
			(start -0.508 0.9398)
			(end 0.508 -0.9398)
			(stroke
				(width 0)
				(type default)
			)
			(fill no)
			(layer "F.CrtYd")
		)
		(fp_rect
			(start -0.508 0.9398)
			(end 0.508 -0.9398)
			(stroke
				(width 0)
				(type default)
			)
			(fill no)
			(layer "F.Fab")
		)
		(pad "1" smd custom
			(at 0 -0.4445 270)
			(size 0.1397 0.1397)
			(layers "F.Cu" "F.Mask" "F.Paste")
			(net "DPB_PWR_BTN_BUF_B")
			(options
				(clearance outline)
				(anchor circle)
			)
			(primitives
				(gr_poly
					(pts
						(arc
							(start -0.1778 -0.2794)
							(mid -0.249642 -0.249642)
							(end -0.2794 -0.1778)
						)
						(arc
							(start -0.2794 0.1778)
							(mid -0.249642 0.249642)
							(end -0.1778 0.2794)
						)
						(arc
							(start 0.1778 0.2794)
							(mid 0.249642 0.249642)
							(end 0.2794 0.1778)
						)
						(arc
							(start 0.2794 -0.1778)
							(mid 0.249642 -0.249642)
							(end 0.1778 -0.2794)
						)
					)
					(width 0)
					(fill yes)
				)
			)
		)
		(pad "2" smd custom
			(at 0 0.4445 270)
			(size 0.1397 0.1397)
			(layers "F.Cu" "F.Mask" "F.Paste")
			(net "DPB_PWR_BTN_B")
			(options
				(clearance outline)
				(anchor circle)
			)
			(primitives
				(gr_poly
					(pts
						(arc
							(start -0.1778 -0.2794)
							(mid -0.249642 -0.249642)
							(end -0.2794 -0.1778)
						)
						(arc
							(start -0.2794 0.1778)
							(mid -0.249642 0.249642)
							(end -0.1778 0.2794)
						)
						(arc
							(start 0.1778 0.2794)
							(mid 0.249642 0.249642)
							(end 0.2794 0.1778)
						)
						(arc
							(start 0.2794 -0.1778)
							(mid 0.249642 -0.249642)
							(end 0.1778 -0.2794)
						)
					)
					(width 0)
					(fill yes)
				)
			)
		)
	)
	(footprint ""
		(layer "F.Cu")
		(at 458.3049 -157.585918)
		(property "Reference" "R649"
			(at 0 0 0)
			(layer "F.SilkS")
			(hide yes)
			(effects
				(font
					(size 1.27 1.27)
				)
			)
		)
		(property "Value" "4K7R2J-2-GP"
			(at 0.064008 -3.993896 0)
			(unlocked yes)
			(layer "F.Fab")
			(hide yes)
			(effects
				(font
					(size 1.016 1.016)
					(thickness 0.1524)
				)
			)
		)
		(property "Device Type" "R402H16"
			(at 0.064008 -5.517896 0)
			(unlocked yes)
			(layer "F.Fab")
			(hide yes)
			(effects
				(font
					(size 1.016 1.016)
					(thickness 0.1524)
				)
			)
		)
		(duplicate_pad_numbers_are_jumpers no)
		(fp_line
			(start -0.508 -0.9398)
			(end -0.508 0.9398)
			(stroke
				(width 0.1524)
				(type default)
			)
			(layer "F.SilkS")
		)
		(fp_line
			(start 0.508 -0.9398)
			(end -0.508 -0.9398)
			(stroke
				(width 0.1524)
				(type default)
			)
			(layer "F.SilkS")
		)
		(fp_rect
			(start -0.508 0.9398)
			(end 0.508 -0.9398)
			(stroke
				(width 0)
				(type default)
			)
			(fill no)
			(layer "F.CrtYd")
		)
		(fp_rect
			(start -0.508 0.9398)
			(end 0.508 -0.9398)
			(stroke
				(width 0)
				(type default)
			)
			(fill no)
			(layer "F.Fab")
		)
		(pad "1" smd custom
			(at 0 -0.4445)
			(size 0.1397 0.1397)
			(layers "F.Cu" "F.Mask" "F.Paste")
			(net "SW_PWR_R_HDD22")
			(options
				(clearance outline)
				(anchor circle)
			)
			(primitives
				(gr_poly
					(pts
						(arc
							(start -0.1778 -0.2794)
							(mid -0.249642 -0.249642)
							(end -0.2794 -0.1778)
						)
						(arc
							(start -0.2794 0.1778)
							(mid -0.249642 0.249642)
							(end -0.1778 0.2794)
						)
						(arc
							(start 0.1778 0.2794)
							(mid 0.249642 0.249642)
							(end 0.2794 0.1778)
						)
						(arc
							(start 0.2794 -0.1778)
							(mid 0.249642 -0.249642)
							(end 0.1778 -0.2794)
						)
					)
					(width 0)
					(fill yes)
				)
			)
		)
		(pad "2" smd custom
			(at 0 0.4445)
			(size 0.1397 0.1397)
			(layers "F.Cu" "F.Mask" "F.Paste")
			(net "GND")
			(options
				(clearance outline)
				(anchor circle)
			)
			(primitives
				(gr_poly
					(pts
						(arc
							(start -0.1778 -0.2794)
							(mid -0.249642 -0.249642)
							(end -0.2794 -0.1778)
						)
						(arc
							(start -0.2794 0.1778)
							(mid -0.249642 0.249642)
							(end -0.1778 0.2794)
						)
						(arc
							(start 0.1778 0.2794)
							(mid 0.249642 0.249642)
							(end 0.2794 0.1778)
						)
						(arc
							(start 0.2794 -0.1778)
							(mid 0.249642 -0.249642)
							(end 0.1778 -0.2794)
						)
					)
					(width 0)
					(fill yes)
				)
			)
		)
	)
	(footprint ""
		(layer "F.Cu")
		(at 27.524202 -253.29515 180)
		(property "Reference" "R1222"
			(at 0 0 180)
			(layer "F.SilkS")
			(hide yes)
			(effects
				(font
					(size 1.27 1.27)
				)
			)
		)
		(property "Value" "619KR2F-GP"
			(at 0.064008 -3.993896 180)
			(unlocked yes)
			(layer "F.Fab")
			(hide yes)
			(effects
				(font
					(size 1.016 1.016)
					(thickness 0.1524)
				)
			)
		)
		(property "Device Type" "R402H16"
			(at 0.064008 -5.517896 180)
			(unlocked yes)
			(layer "F.Fab")
			(hide yes)
			(effects
				(font
					(size 1.016 1.016)
					(thickness 0.1524)
				)
			)
		)
		(duplicate_pad_numbers_are_jumpers no)
		(fp_line
			(start 0.508 -0.9398)
			(end -0.508 -0.9398)
			(stroke
				(width 0.1524)
				(type default)
			)
			(layer "F.SilkS")
		)
		(fp_line
			(start -0.508 -0.9398)
			(end -0.508 0.9398)
			(stroke
				(width 0.1524)
				(type default)
			)
			(layer "F.SilkS")
		)
		(fp_rect
			(start -0.508 0.9398)
			(end 0.508 -0.9398)
			(stroke
				(width 0)
				(type default)
			)
			(fill no)
			(layer "F.CrtYd")
		)
		(fp_rect
			(start -0.508 0.9398)
			(end 0.508 -0.9398)
			(stroke
				(width 0)
				(type default)
			)
			(fill no)
			(layer "F.Fab")
		)
		(pad "1" smd custom
			(at 0 -0.4445 180)
			(size 0.1397 0.1397)
			(layers "F.Cu" "F.Mask" "F.Paste")
			(net "P5V_A_RF")
			(options
				(clearance outline)
				(anchor circle)
			)
			(primitives
				(gr_poly
					(pts
						(arc
							(start -0.1778 -0.2794)
							(mid -0.249642 -0.249642)
							(end -0.2794 -0.1778)
						)
						(arc
							(start -0.2794 0.1778)
							(mid -0.249642 0.249642)
							(end -0.1778 0.2794)
						)
						(arc
							(start 0.1778 0.2794)
							(mid 0.249642 0.249642)
							(end 0.2794 0.1778)
						)
						(arc
							(start 0.2794 -0.1778)
							(mid 0.249642 -0.249642)
							(end 0.1778 -0.2794)
						)
					)
					(width 0)
					(fill yes)
				)
			)
		)
		(pad "2" smd custom
			(at 0 0.4445 180)
			(size 0.1397 0.1397)
			(layers "F.Cu" "F.Mask" "F.Paste")
			(net "AGND_P5V_A")
			(options
				(clearance outline)
				(anchor circle)
			)
			(primitives
				(gr_poly
					(pts
						(arc
							(start -0.1778 -0.2794)
							(mid -0.249642 -0.249642)
							(end -0.2794 -0.1778)
						)
						(arc
							(start -0.2794 0.1778)
							(mid -0.249642 0.249642)
							(end -0.1778 0.2794)
						)
						(arc
							(start 0.1778 0.2794)
							(mid 0.249642 0.249642)
							(end 0.2794 0.1778)
						)
						(arc
							(start 0.2794 -0.1778)
							(mid 0.249642 -0.249642)
							(end 0.1778 -0.2794)
						)
					)
					(width 0)
					(fill yes)
				)
			)
		)
	)
)
